(kicad_pcb
	(version 20241229)
	(generator "pcbnew")
	(generator_version "9.0")
	(general
		(thickness 1.711)
		(legacy_teardrops no)
	)
	(paper "A4")
	(title_block
		(title "Antmicro Baseboard for Jetson AGX Thor")
		(date "2026-02-18")
		(rev "1.1.0")
		(company "Antmicro Ltd")
		(comment 1 "www.antmicro.com")
		(comment 9 "footprints 823-827 of 1170")
	)
	(layers
		(0 "F.Cu" signal)
		(4 "In1.Cu" signal)
		(6 "In2.Cu" signal)
		(8 "In3.Cu" signal)
		(10 "In4.Cu" jumper)
		(12 "In5.Cu" signal)
		(14 "In6.Cu" signal)
		(16 "In7.Cu" signal)
		(18 "In8.Cu" signal)
		(2 "B.Cu" signal)
		(9 "F.Adhes" user "F.Adhesive")
		(11 "B.Adhes" user "B.Adhesive")
		(13 "F.Paste" user)
		(15 "B.Paste" user)
		(5 "F.SilkS" user "F.Silkscreen")
		(7 "B.SilkS" user "B.Silkscreen")
		(1 "F.Mask" user)
		(3 "B.Mask" user)
		(17 "Dwgs.User" user "User.Drawings")
		(19 "Cmts.User" user "User.Comments")
		(21 "Eco1.User" user "User.Eco1")
		(23 "Eco2.User" user "User.Eco2")
		(25 "Edge.Cuts" user)
		(27 "Margin" user)
		(31 "F.CrtYd" user "F.Courtyard")
		(29 "B.CrtYd" user "B.Courtyard")
		(35 "F.Fab" user)
		(33 "B.Fab" user)
	)
	(footprint "antmicro-footprints:C_0402_1005Metric"
		(layer "B.Cu")
		(at 160.3 69.79 180)
		(descr "Capacitor SMD 0402")
		(tags "capacitor SMD 0402")
		(property "Reference" "C238"
			(at -1.26 -1.44 0)
			(layer "B.SilkS")
			(effects
				(font
					(size 0.7 0.7)
					(thickness 0.15)
				)
				(justify left bottom mirror)
			)
		)
		(property "Value" "C_100n_0402"
			(at -1.022927 -2.155213 0)
			(layer "B.Fab")
			(effects
				(font
					(size 0.7 0.7)
					(thickness 0.15)
				)
				(justify left bottom mirror)
			)
		)
		(property "Datasheet" "https://www.murata.com/products/productdetail?partno=GRM155R61H104KE14%23"
			(at 0 0 0)
			(layer "B.Fab")
			(hide yes)
			(effects
				(font
					(size 1.27 1.27)
					(thickness 0.15)
				)
				(justify mirror)
			)
		)
		(property "Description" "SMD Multilayer Ceramic Capacitor, 0.1 µF, 50 V, 0402 [1005 Metric], ± 10%, X5R, GRM Series"
			(at 0 0 0)
			(layer "B.Fab")
			(hide yes)
			(effects
				(font
					(size 1.27 1.27)
					(thickness 0.15)
				)
				(justify mirror)
			)
		)
		(property "MPN" "GRM155R61H104KE14D"
			(at 0 0 0)
			(unlocked yes)
			(layer "B.Fab")
			(hide yes)
			(effects
				(font
					(size 1 1)
					(thickness 0.15)
				)
				(justify mirror)
			)
		)
		(property "Val" "100n"
			(at 0 0 0)
			(unlocked yes)
			(layer "B.Fab")
			(hide yes)
			(effects
				(font
					(size 1 1)
					(thickness 0.15)
				)
				(justify mirror)
			)
		)
		(property "Voltage" "50V"
			(at 0 0 0)
			(unlocked yes)
			(layer "B.Fab")
			(hide yes)
			(effects
				(font
					(size 1 1)
					(thickness 0.15)
				)
				(justify mirror)
			)
		)
		(property "Dielectric" "X5R"
			(at 0 0 0)
			(unlocked yes)
			(layer "B.Fab")
			(hide yes)
			(effects
				(font
					(size 1 1)
					(thickness 0.15)
				)
				(justify mirror)
			)
		)
		(property "Manufacturer" "Murata"
			(at 0 0 0)
			(unlocked yes)
			(layer "B.Fab")
			(hide yes)
			(effects
				(font
					(size 1 1)
					(thickness 0.15)
				)
				(justify mirror)
			)
		)
		(property "License" "Apache-2.0"
			(at 0 0 0)
			(unlocked yes)
			(layer "B.Fab")
			(hide yes)
			(effects
				(font
					(size 1 1)
					(thickness 0.15)
				)
				(justify mirror)
			)
		)
		(property "Author" "Antmicro"
			(at 0 0 0)
			(unlocked yes)
			(layer "B.Fab")
			(hide yes)
			(effects
				(font
					(size 1 1)
					(thickness 0.15)
				)
				(justify mirror)
			)
		)
		(sheetname "/SoM_IO2/")
		(sheetfile "som_io2.kicad_sch")
		(attr smd exclude_from_pos_files exclude_from_bom dnp)
		(fp_rect
			(start -0.925 0.47)
			(end 0.925 -0.47)
			(stroke
				(width 0.05)
				(type default)
			)
			(fill no)
			(layer "B.CrtYd")
		)
		(fp_line
			(start 0.504 0.25)
			(end 0.504 -0.248)
			(stroke
				(width 0.15)
				(type solid)
			)
			(layer "B.Fab")
		)
		(fp_line
			(start 0.504 -0.248)
			(end -0.494 -0.248)
			(stroke
				(width 0.15)
				(type solid)
			)
			(layer "B.Fab")
		)
		(fp_line
			(start -0.494 0.25)
			(end 0.504 0.25)
			(stroke
				(width 0.15)
				(type solid)
			)
			(layer "B.Fab")
		)
		(fp_line
			(start -0.494 -0.248)
			(end -0.494 0.25)
			(stroke
				(width 0.15)
				(type solid)
			)
			(layer "B.Fab")
		)
		(fp_text user "License: Apache-2.0"
			(at -0.939 -5.799 0)
			(layer "B.Fab")
			(effects
				(font
					(size 0.7 0.7)
					(thickness 0.15)
				)
				(justify left bottom mirror)
			)
		)
		(fp_text user "${REFERENCE}"
			(at -0.939 -4.599 0)
			(layer "B.Fab")
			(effects
				(font
					(size 0.7 0.7)
					(thickness 0.15)
				)
				(justify left bottom mirror)
			)
		)
		(fp_text user "Author: Antmicro"
			(at -0.939 -3.399 0)
			(layer "B.Fab")
			(effects
				(font
					(size 0.7 0.7)
					(thickness 0.15)
				)
				(justify left bottom mirror)
			)
		)
		(pad "1" smd roundrect
			(at -0.48 0 180)
			(size 0.59 0.64)
			(layers "B.Cu" "B.Mask" "B.Paste")
			(roundrect_rratio 0.25)
			(net 1 "GND")
			(pintype "passive")
		)
		(pad "2" smd roundrect
			(at 0.48 0 180)
			(size 0.59 0.64)
			(layers "B.Cu" "B.Mask" "B.Paste")
			(roundrect_rratio 0.25)
			(net 11 "+1V8")
			(pintype "passive")
		)
	)
	(footprint "antmicro-footprints:R_0402_1005Metric"
		(layer "B.Cu")
		(at 124.6 109.8 180)
		(descr "Resistor SMD 0402")
		(tags "resistor SMD 0402")
		(property "Reference" "R208"
			(at -3.9 -0.36 0)
			(layer "B.SilkS")
			(effects
				(font
					(size 0.7 0.7)
					(thickness 0.15)
				)
				(justify left bottom mirror)
			)
		)
		(property "Value" "R_0R_0402"
			(at -1.011843 -1.772046 0)
			(layer "B.Fab")
			(effects
				(font
					(size 0.7 0.7)
					(thickness 0.15)
				)
				(justify left bottom mirror)
			)
		)
		(property "Datasheet" "https://industrial.panasonic.com/cdbs/www-data/pdf/RDA0000/AOA0000C301.pdf"
			(at 0 0 0)
			(layer "B.Fab")
			(hide yes)
			(effects
				(font
					(size 1.27 1.27)
					(thickness 0.15)
				)
				(justify mirror)
			)
		)
		(property "Description" "SMD Chip Resistor, Jumper, 0 ohm, 100 mW, 0402 [1005 Metric], Thick Film, General Purpose"
			(at 0 0 0)
			(layer "B.Fab")
			(hide yes)
			(effects
				(font
					(size 1.27 1.27)
					(thickness 0.15)
				)
				(justify mirror)
			)
		)
		(property "MPN" "ERJ2GE0R00X"
			(at 0 0 0)
			(unlocked yes)
			(layer "B.Fab")
			(hide yes)
			(effects
				(font
					(size 1 1)
					(thickness 0.15)
				)
				(justify mirror)
			)
		)
		(property "Manufacturer" "Panasonic"
			(at 0 0 0)
			(unlocked yes)
			(layer "B.Fab")
			(hide yes)
			(effects
				(font
					(size 1 1)
					(thickness 0.15)
				)
				(justify mirror)
			)
		)
		(property "License" "Apache-2.0"
			(at 0 0 0)
			(unlocked yes)
			(layer "B.Fab")
			(hide yes)
			(effects
				(font
					(size 1 1)
					(thickness 0.15)
				)
				(justify mirror)
			)
		)
		(property "Author" "Antmicro"
			(at 0 0 0)
			(unlocked yes)
			(layer "B.Fab")
			(hide yes)
			(effects
				(font
					(size 1 1)
					(thickness 0.15)
				)
				(justify mirror)
			)
		)
		(property "Val" "0R"
			(at 0 0 0)
			(unlocked yes)
			(layer "B.Fab")
			(hide yes)
			(effects
				(font
					(size 1 1)
					(thickness 0.15)
				)
				(justify mirror)
			)
		)
		(property "Tolerance" "~"
			(at 0 0 0)
			(unlocked yes)
			(layer "B.Fab")
			(hide yes)
			(effects
				(font
					(size 1 1)
					(thickness 0.15)
				)
				(justify mirror)
			)
		)
		(property "Current" "1A"
			(at 0 0 0)
			(unlocked yes)
			(layer "B.Fab")
			(hide yes)
			(effects
				(font
					(size 1 1)
					(thickness 0.15)
				)
				(justify mirror)
			)
		)
		(sheetname "/M.2/")
		(sheetfile "m2.kicad_sch")
		(attr smd)
		(fp_poly
			(pts
				(xy -0.925 0.47) (xy 0.925 0.47) (xy 0.925 -0.47) (xy -0.925 -0.47)
			)
			(stroke
				(width 0.05)
				(type default)
			)
			(fill no)
			(layer "B.CrtYd")
		)
		(fp_poly
			(pts
				(xy -0.5 0.25) (xy 0.5 0.25) (xy 0.5 -0.25) (xy -0.5 -0.25)
			)
			(stroke
				(width 0.15)
				(type solid)
			)
			(fill no)
			(layer "B.Fab")
		)
		(fp_text user "Author: Antmicro"
			(at -0.95 -4.169 0)
			(layer "B.Fab")
			(effects
				(font
					(size 0.7 0.7)
					(thickness 0.15)
				)
				(justify left bottom mirror)
			)
		)
		(fp_text user "${REFERENCE}"
			(at -0.95 -3.168 0)
			(layer "B.Fab")
			(effects
				(font
					(size 0.7 0.7)
					(thickness 0.15)
				)
				(justify left bottom mirror)
			)
		)
		(fp_text user "License: Apache-2.0"
			(at -0.949999 -5.169 0)
			(layer "B.Fab")
			(effects
				(font
					(size 0.7 0.7)
					(thickness 0.15)
				)
				(justify left bottom mirror)
			)
		)
		(pad "1" smd roundrect
			(at -0.48 0 180)
			(size 0.59 0.64)
			(layers "B.Cu" "B.Mask" "B.Paste")
			(roundrect_rratio 0.25)
			(net 104 "/M.2/~{PEWAKE}")
			(pintype "passive")
		)
		(pad "2" smd roundrect
			(at 0.48 0 180)
			(size 0.59 0.64)
			(layers "B.Cu" "B.Mask" "B.Paste")
			(roundrect_rratio 0.25)
			(net 826 "/M.2/~{PEWAKE_M}")
			(pintype "passive")
		)
	)
	(footprint "antmicro-footprints:TP_SMD_0.75mm"
		(layer "B.Cu")
		(at 185.48 76.67 180)
		(property "Reference" "TP124"
			(at -3.850001 -0.38 0)
			(layer "B.SilkS")
			(effects
				(font
					(size 0.7 0.7)
					(thickness 0.15)
				)
				(justify left bottom mirror)
			)
		)
		(property "Value" "TP_0.75mm_SMD"
			(at 0 -1.2 0)
			(layer "B.Fab")
			(effects
				(font
					(size 0.7 0.7)
					(thickness 0.15)
				)
				(justify left bottom mirror)
			)
		)
		(property "Description" "SMT test point"
			(at 0 0 0)
			(layer "B.Fab")
			(hide yes)
			(effects
				(font
					(size 1.27 1.27)
					(thickness 0.15)
				)
				(justify mirror)
			)
		)
		(property "MPN" ""
			(at 0 0 0)
			(unlocked yes)
			(layer "B.Fab")
			(hide yes)
			(effects
				(font
					(size 1 1)
					(thickness 0.15)
				)
				(justify mirror)
			)
		)
		(property "Manufacturer" ""
			(at 0 0 0)
			(unlocked yes)
			(layer "B.Fab")
			(hide yes)
			(effects
				(font
					(size 1 1)
					(thickness 0.15)
				)
				(justify mirror)
			)
		)
		(property "Author" "Antmicro"
			(at 0 0 0)
			(unlocked yes)
			(layer "B.Fab")
			(hide yes)
			(effects
				(font
					(size 1 1)
					(thickness 0.15)
				)
				(justify mirror)
			)
		)
		(property "License" "Apache-2.0"
			(at 0 0 0)
			(unlocked yes)
			(layer "B.Fab")
			(hide yes)
			(effects
				(font
					(size 1 1)
					(thickness 0.15)
				)
				(justify mirror)
			)
		)
		(sheetname "/Power/")
		(sheetfile "power.kicad_sch")
		(attr exclude_from_pos_files exclude_from_bom)
		(fp_circle
			(center 0 0)
			(end 0.475 0)
			(stroke
				(width 0.05)
				(type default)
			)
			(fill no)
			(layer "B.CrtYd")
		)
		(fp_text user "License: Apache-2.0"
			(at -0.4 -5.101 0)
			(layer "B.Fab")
			(effects
				(font
					(size 0.7 0.7)
					(thickness 0.15)
				)
				(justify left bottom mirror)
			)
		)
		(fp_text user "${REFERENCE}"
			(at -0.4 -2.7 0)
			(layer "B.Fab")
			(effects
				(font
					(size 0.7 0.7)
					(thickness 0.15)
				)
				(justify left bottom mirror)
			)
		)
		(fp_text user "Author: Antmicro"
			(at -0.4 -3.901 0)
			(layer "B.Fab")
			(effects
				(font
					(size 0.7 0.7)
					(thickness 0.15)
				)
				(justify left bottom mirror)
			)
		)
		(pad "1" smd circle
			(at 0 0 180)
			(size 0.75 0.75)
			(layers "B.Cu" "B.Mask")
			(net 525 "/Power/USBPD2_HV")
			(pinfunction "1")
			(pintype "passive")
		)
	)
	(footprint "antmicro-footprints:SOT-523"
		(layer "B.Cu")
		(at 213.8 75.702 -90)
		(property "Reference" "Q12"
			(at -1.102 -0.5 270)
			(layer "B.SilkS")
			(effects
				(font
					(size 0.7 0.7)
					(thickness 0.15)
				)
				(justify right top mirror)
			)
		)
		(property "Value" "DMG1012T-7"
			(at 0.1 -1.824 90)
			(layer "B.Fab")
			(effects
				(font
					(size 0.7 0.7)
					(thickness 0.15)
				)
				(justify left bottom mirror)
			)
		)
		(property "Datasheet" "https://www.diodes.com/assets/Datasheets/ds31783.pdf"
			(at 0 0 90)
			(layer "B.Fab")
			(hide yes)
			(effects
				(font
					(size 1.27 1.27)
					(thickness 0.15)
				)
				(justify mirror)
			)
		)
		(property "Description" "Power MOSFET, N Channel, 20 V, 630 mA, 0.3 ohm, SOT-523, Surface Mount"
			(at 0 0 90)
			(layer "B.Fab")
			(hide yes)
			(effects
				(font
					(size 1.27 1.27)
					(thickness 0.15)
				)
				(justify mirror)
			)
		)
		(property "MPN" "DMG1012T-7"
			(at 0 0 90)
			(unlocked yes)
			(layer "B.Fab")
			(hide yes)
			(effects
				(font
					(size 1 1)
					(thickness 0.15)
				)
				(justify mirror)
			)
		)
		(property "Manufacturer" "Diodes Incorporated"
			(at 0 0 90)
			(unlocked yes)
			(layer "B.Fab")
			(hide yes)
			(effects
				(font
					(size 1 1)
					(thickness 0.15)
				)
				(justify mirror)
			)
		)
		(property "Author" "Antmicro"
			(at 0 0 90)
			(unlocked yes)
			(layer "B.Fab")
			(hide yes)
			(effects
				(font
					(size 1 1)
					(thickness 0.15)
				)
				(justify mirror)
			)
		)
		(property "License" "Apache-2.0"
			(at 0 0 90)
			(unlocked yes)
			(layer "B.Fab")
			(hide yes)
			(effects
				(font
					(size 1 1)
					(thickness 0.15)
				)
				(justify mirror)
			)
		)
		(sheetname "/USB Debug, PD/")
		(sheetfile "usb_debug_pd.kicad_sch")
		(attr smd)
		(fp_line
			(start -0.725 0.551)
			(end -0.277 0.551)
			(stroke
				(width 0.15)
				(type solid)
			)
			(layer "B.SilkS")
		)
		(fp_line
			(start -0.277 0.551)
			(end -0.277 0.75)
			(stroke
				(width 0.15)
				(type solid)
			)
			(layer "B.SilkS")
		)
		(fp_line
			(start -0.927 0.351)
			(end -0.725 0.551)
			(stroke
				(width 0.15)
				(type solid)
			)
			(layer "B.SilkS")
		)
		(fp_line
			(start -0.927 0.051)
			(end -0.927 0.351)
			(stroke
				(width 0.15)
				(type solid)
			)
			(layer "B.SilkS")
		)
		(fp_circle
			(center -0.9652 -0.9652)
			(end -0.9152 -0.9652)
			(stroke
				(width 0.15)
				(type solid)
			)
			(fill yes)
			(layer "B.SilkS")
		)
		(fp_line
			(start -1.12 1.16)
			(end 1.1 1.16)
			(stroke
				(width 0.05)
				(type solid)
			)
			(layer "B.CrtYd")
		)
		(fp_line
			(start -1.12 1.16)
			(end -1.12 -1.15)
			(stroke
				(width 0.05)
				(type solid)
			)
			(layer "B.CrtYd")
		)
		(fp_line
			(start 1.1 1.16)
			(end 1.1 -1.15)
			(stroke
				(width 0.05)
				(type solid)
			)
			(layer "B.CrtYd")
		)
		(fp_line
			(start -1.12 -1.15)
			(end 1.1 -1.15)
			(stroke
				(width 0.05)
				(type solid)
			)
			(layer "B.CrtYd")
		)
		(fp_line
			(start -0.652 0.425)
			(end -0.802 0.276)
			(stroke
				(width 0.15)
				(type solid)
			)
			(layer "B.Fab")
		)
		(fp_line
			(start 0.8 0.425)
			(end -0.652 0.425)
			(stroke
				(width 0.15)
				(type solid)
			)
			(layer "B.Fab")
		)
		(fp_line
			(start 0.8 0.425)
			(end 0.8 -0.424)
			(stroke
				(width 0.15)
				(type solid)
			)
			(layer "B.Fab")
		)
		(fp_line
			(start -0.802 0.276)
			(end -0.802 -0.424)
			(stroke
				(width 0.15)
				(type solid)
			)
			(layer "B.Fab")
		)
		(fp_line
			(start 0.8 -0.424)
			(end -0.802 -0.424)
			(stroke
				(width 0.15)
				(type solid)
			)
			(layer "B.Fab")
		)
		(fp_circle
			(center -0.9652 -0.9652)
			(end -0.9144 -0.9652)
			(stroke
				(width 0.15)
				(type solid)
			)
			(fill no)
			(layer "B.Fab")
		)
		(fp_text user "Author: Antmicro"
			(at -1.12 -6.224 90)
			(layer "B.Fab")
			(effects
				(font
					(size 0.7 0.7)
					(thickness 0.15)
				)
				(justify left bottom mirror)
			)
		)
		(fp_text user "License: Apache-2.0"
			(at -1.12 -5.024 90)
			(layer "B.Fab")
			(effects
				(font
					(size 0.7 0.7)
					(thickness 0.15)
				)
				(justify left bottom mirror)
			)
		)
		(fp_text user "${REFERENCE}"
			(at -1.12 -3.824 90)
			(layer "B.Fab")
			(effects
				(font
					(size 0.7 0.7)
					(thickness 0.15)
				)
				(justify left bottom mirror)
			)
		)
		(pad "1" smd rect
			(at -0.5 -0.65 270)
			(size 0.4 0.51)
			(layers "B.Cu" "B.Mask" "B.Paste")
			(net 537 "/USB Debug, PD/FTDI_LED_RX")
			(pinfunction "G")
			(pintype "input")
		)
		(pad "2" smd rect
			(at 0.498 -0.65 270)
			(size 0.4 0.51)
			(layers "B.Cu" "B.Mask" "B.Paste")
			(net 1 "GND")
			(pinfunction "S")
			(pintype "passive")
		)
		(pad "3" smd rect
			(at 0 0.652 270)
			(size 0.4 0.51)
			(layers "B.Cu" "B.Mask" "B.Paste")
			(net 881 "/USB Debug, PD/FTDI_CBUS_EN")
			(pinfunction "D")
			(pintype "passive")
		)
	)
	(footprint "antmicro-footprints:R_0402_1005Metric"
		(layer "B.Cu")
		(at 175.25 57.5 -90)
		(descr "Resistor SMD 0402")
		(tags "resistor SMD 0402")
		(property "Reference" "R61"
			(at -3.58 -0.365532 90)
			(layer "B.SilkS")
			(effects
				(font
					(size 0.7 0.7)
					(thickness 0.15)
				)
				(justify left bottom mirror)
			)
		)
		(property "Value" "R_470R_0402"
			(at -1.011843 -1.772046 90)
			(layer "B.Fab")
			(effects
				(font
					(size 0.7 0.7)
					(thickness 0.15)
				)
				(justify left bottom mirror)
			)
		)
		(property "Datasheet" "https://www.bourns.com/docs/product-datasheets/cr.pdf"
			(at 0 0 90)
			(layer "B.Fab")
			(hide yes)
			(effects
				(font
					(size 1.27 1.27)
					(thickness 0.15)
				)
				(justify mirror)
			)
		)
		(property "Description" "SMD Chip Resistor, 470 ohm, ± 1%, 62.5 mW, 0402 [1005 Metric], Thick Film, General Purpose"
			(at 0 0 90)
			(layer "B.Fab")
			(hide yes)
			(effects
				(font
					(size 1.27 1.27)
					(thickness 0.15)
				)
				(justify mirror)
			)
		)
		(property "MPN" "CR0402-FX-4700GLF"
			(at 0 0 90)
			(unlocked yes)
			(layer "B.Fab")
			(hide yes)
			(effects
				(font
					(size 1 1)
					(thickness 0.15)
				)
				(justify mirror)
			)
		)
		(property "Manufacturer" "Bourns"
			(at 0 0 90)
			(unlocked yes)
			(layer "B.Fab")
			(hide yes)
			(effects
				(font
					(size 1 1)
					(thickness 0.15)
				)
				(justify mirror)
			)
		)
		(property "License" "Apache-2.0"
			(at 0 0 90)
			(unlocked yes)
			(layer "B.Fab")
			(hide yes)
			(effects
				(font
					(size 1 1)
					(thickness 0.15)
				)
				(justify mirror)
			)
		)
		(property "Author" "Antmicro"
			(at 0 0 90)
			(unlocked yes)
			(layer "B.Fab")
			(hide yes)
			(effects
				(font
					(size 1 1)
					(thickness 0.15)
				)
				(justify mirror)
			)
		)
		(property "Val" "470R"
			(at 0 0 90)
			(unlocked yes)
			(layer "B.Fab")
			(hide yes)
			(effects
				(font
					(size 1 1)
					(thickness 0.15)
				)
				(justify mirror)
			)
		)
		(property "Tolerance" "1%"
			(at 0 0 90)
			(unlocked yes)
			(layer "B.Fab")
			(hide yes)
			(effects
				(font
					(size 1 1)
					(thickness 0.15)
				)
				(justify mirror)
			)
		)
		(sheetname "/Power/")
		(sheetfile "power.kicad_sch")
		(attr smd)
		(fp_poly
			(pts
				(xy -0.925 0.47) (xy -0.925 -0.47) (xy 0.925 -0.47) (xy 0.925 0.47)
			)
			(stroke
				(width 0.05)
				(type default)
			)
			(fill no)
			(layer "B.CrtYd")
		)
		(fp_poly
			(pts
				(xy -0.5 0.25) (xy -0.5 -0.25) (xy 0.5 -0.25) (xy 0.5 0.25)
			)
			(stroke
				(width 0.15)
				(type solid)
			)
			(fill no)
			(layer "B.Fab")
		)
		(fp_text user "Author: Antmicro"
			(at -0.95 -4.169 90)
			(layer "B.Fab")
			(effects
				(font
					(size 0.7 0.7)
					(thickness 0.15)
				)
				(justify left bottom mirror)
			)
		)
		(fp_text user "${REFERENCE}"
			(at -0.95 -3.168 90)
			(layer "B.Fab")
			(effects
				(font
					(size 0.7 0.7)
					(thickness 0.15)
				)
				(justify left bottom mirror)
			)
		)
		(fp_text user "License: Apache-2.0"
			(at -0.949999 -5.169 90)
			(layer "B.Fab")
			(effects
				(font
					(size 0.7 0.7)
					(thickness 0.15)
				)
				(justify left bottom mirror)
			)
		)
		(pad "1" smd roundrect
			(at -0.48 0 270)
			(size 0.59 0.64)
			(layers "B.Cu" "B.Mask" "B.Paste")
			(roundrect_rratio 0.25)
			(net 1286 "Net-(D61-A)")
			(pintype "passive")
		)
		(pad "2" smd roundrect
			(at 0.48 0 270)
			(size 0.59 0.64)
			(layers "B.Cu" "B.Mask" "B.Paste")
			(roundrect_rratio 0.25)
			(net 213 "+5V_SOM")
			(pintype "passive")
		)
	)
)
